(kicad_pcb
	(version 20260206)
	(generator "pcbnew")
	(generator_version "10.0")
	(general
		(thickness 1.6)
		(legacy_teardrops no)
	)
	(paper "A4")
	(title_block
		(title "Bryce Canyon_SCC_16316-1_OCP.brd")
		(comment 1 "Bryce Canyon / footprints 1274-1281 of 1561")
	)
	(layers
		(0 "F.Cu" signal "TOP")
		(4 "In1.Cu" signal "L2GND")
		(6 "In2.Cu" signal "L3")
		(8 "In3.Cu" signal "L4VCC")
		(10 "In4.Cu" signal "L5VCC")
		(12 "In5.Cu" signal "L6")
		(14 "In6.Cu" signal "L7GND")
		(2 "B.Cu" signal "BOTTOM")
		(9 "F.Adhes" user "F.Adhesive")
		(11 "B.Adhes" user "B.Adhesive")
		(13 "F.Paste" user "Package Geometry/Pastemask Top")
		(15 "B.Paste" user "Package Geometry/Pastemask Bottom")
		(5 "F.SilkS" user "Ref Des/Silkscreen Top")
		(7 "B.SilkS" user "Ref Des/Silkscreen Bottom")
		(1 "F.Mask" user "Board Geometry/Soldermask Top")
		(3 "B.Mask" user "Board Geometry/Soldermask Bottom")
		(17 "Dwgs.User" user "User.Drawings")
		(19 "Cmts.User" user "User.Comments")
		(21 "Eco1.User" user "User.Eco1")
		(23 "Eco2.User" user "User.Eco2")
		(25 "Edge.Cuts" user "Board Geometry/Outline")
		(27 "Margin" user)
		(31 "F.CrtYd" user "Package Geometry/Place Bound Top")
		(29 "B.CrtYd" user "Package Geometry/Place Bound Bottom")
		(35 "F.Fab" user "Ref Des/Assembly Top")
		(33 "B.Fab" user "Ref Des/Assembly Bottom")
	)
	(footprint ""
		(layer "B.Cu")
		(at 176.276 -53.3908 -90)
		(property "Reference" "R498"
			(at 0 0 90)
			(layer "B.SilkS")
			(hide yes)
			(effects
				(font
					(size 1.27 1.27)
				)
				(justify mirror)
			)
		)
		(property "Value" "0R2J-2-GP"
			(at -0.064008 -3.993896 270)
			(unlocked yes)
			(layer "B.Fab")
			(hide yes)
			(effects
				(font
					(size 1.016 1.016)
					(thickness 0.1524)
				)
				(justify mirror)
			)
		)
		(property "Device Type" "R402H16"
			(at -0.064008 -5.517896 270)
			(unlocked yes)
			(layer "B.Fab")
			(hide yes)
			(effects
				(font
					(size 1.016 1.016)
					(thickness 0.1524)
				)
				(justify mirror)
			)
		)
		(duplicate_pad_numbers_are_jumpers no)
		(fp_line
			(start -0.508 -0.9398)
			(end 0.508 -0.9398)
			(stroke
				(width 0.1524)
				(type default)
			)
			(layer "B.SilkS")
		)
		(fp_line
			(start 0.508 -0.9398)
			(end 0.508 0.9398)
			(stroke
				(width 0.1524)
				(type default)
			)
			(layer "B.SilkS")
		)
		(fp_rect
			(start 0.508 0.9398)
			(end -0.508 -0.9398)
			(stroke
				(width 0)
				(type default)
			)
			(fill no)
			(layer "B.CrtYd")
		)
		(fp_rect
			(start 0.508 0.9398)
			(end -0.508 -0.9398)
			(stroke
				(width 0)
				(type default)
			)
			(fill no)
			(layer "B.Fab")
		)
		(pad "1" smd custom
			(at 0 -0.4445 90)
			(size 0.1397 0.1397)
			(layers "B.Cu" "B.Mask" "B.Paste")
			(net "GND")
			(options
				(clearance outline)
				(anchor circle)
			)
			(primitives
				(gr_poly
					(pts
						(arc
							(start -0.1778 0.2794)
							(mid -0.249642 0.249642)
							(end -0.2794 0.1778)
						)
						(arc
							(start -0.2794 -0.1778)
							(mid -0.249642 -0.249642)
							(end -0.1778 -0.2794)
						)
						(arc
							(start 0.1778 -0.2794)
							(mid 0.249642 -0.249642)
							(end 0.2794 -0.1778)
						)
						(arc
							(start 0.2794 0.1778)
							(mid 0.249642 0.249642)
							(end 0.1778 0.2794)
						)
					)
					(width 0)
					(fill yes)
				)
			)
		)
		(pad "2" smd custom
			(at 0 0.4445 90)
			(size 0.1397 0.1397)
			(layers "B.Cu" "B.Mask" "B.Paste")
			(net "GND_SENSE")
			(options
				(clearance outline)
				(anchor circle)
			)
			(primitives
				(gr_poly
					(pts
						(arc
							(start -0.1778 0.2794)
							(mid -0.249642 0.249642)
							(end -0.2794 0.1778)
						)
						(arc
							(start -0.2794 -0.1778)
							(mid -0.249642 -0.249642)
							(end -0.1778 -0.2794)
						)
						(arc
							(start 0.1778 -0.2794)
							(mid 0.249642 -0.249642)
							(end 0.2794 -0.1778)
						)
						(arc
							(start 0.2794 0.1778)
							(mid 0.249642 0.249642)
							(end 0.1778 0.2794)
						)
					)
					(width 0)
					(fill yes)
				)
			)
		)
	)
	(footprint ""
		(layer "B.Cu")
		(at 133.5278 -123.2154 -90)
		(property "Reference" "Q9"
			(at 0 0 90)
			(layer "B.SilkS")
			(hide yes)
			(effects
				(font
					(size 1.27 1.27)
				)
				(justify mirror)
			)
		)
		(property "Value" "SSM3K324R-GP"
			(at -0.127 -8.9662 270)
			(unlocked yes)
			(layer "B.Fab")
			(hide yes)
			(effects
				(font
					(size 1.016 1.016)
					(thickness 0.1524)
				)
				(justify mirror)
			)
		)
		(property "Device Type" "SOT23DGS2D4H35"
			(at -0.127 -10.4902 270)
			(unlocked yes)
			(layer "B.Fab")
			(hide yes)
			(effects
				(font
					(size 1.016 1.016)
					(thickness 0.1524)
				)
				(justify mirror)
			)
		)
		(duplicate_pad_numbers_are_jumpers no)
		(fp_line
			(start -1.651 1.778)
			(end -1.651 -1.778)
			(stroke
				(width 0.1524)
				(type default)
			)
			(layer "B.SilkS")
		)
		(fp_line
			(start 1.651 1.778)
			(end -1.651 1.778)
			(stroke
				(width 0.1524)
				(type default)
			)
			(layer "B.SilkS")
		)
		(fp_line
			(start -1.651 -1.778)
			(end 1.651 -1.778)
			(stroke
				(width 0.1524)
				(type default)
			)
			(layer "B.SilkS")
		)
		(fp_line
			(start 1.651 -1.778)
			(end 1.651 1.778)
			(stroke
				(width 0.1524)
				(type default)
			)
			(layer "B.SilkS")
		)
		(fp_poly
			(pts
				(xy 1.778 1.8796) (xy 1.778 -1.8796) (xy -1.778 -1.8796) (xy -1.778 1.8796)
			)
			(stroke
				(width 0)
				(type default)
			)
			(fill no)
			(layer "B.CrtYd")
		)
		(fp_poly
			(pts
				(xy 1.778 1.8796) (xy 1.778 -1.8796) (xy -1.778 -1.8796) (xy -1.778 1.8796)
			)
			(stroke
				(width 0)
				(type default)
			)
			(fill no)
			(layer "B.Fab")
		)
		(pad "D" smd custom
			(at 0 -0.9525 90)
			(size 0.1905 0.1905)
			(layers "B.Cu" "B.Mask" "B.Paste")
			(net "P12V_STBY_Q10_G")
			(options
				(clearance outline)
				(anchor circle)
			)
			(primitives
				(gr_poly
					(pts
						(arc
							(start -0.1778 -0.5715)
							(mid -0.321484 -0.511984)
							(end -0.381 -0.3683)
						)
						(arc
							(start -0.381 0.3683)
							(mid -0.321484 0.511984)
							(end -0.1778 0.5715)
						)
						(arc
							(start 0.1778 0.5715)
							(mid 0.321484 0.511984)
							(end 0.381 0.3683)
						)
						(arc
							(start 0.381 -0.3683)
							(mid 0.321484 -0.511984)
							(end 0.1778 -0.5715)
						)
					)
					(width 0)
					(fill yes)
				)
			)
		)
		(pad "G" smd custom
			(at 0.98425 0.9525 90)
			(size 0.1905 0.1905)
			(layers "B.Cu" "B.Mask" "B.Paste")
			(net "P1V5_C_G")
			(options
				(clearance outline)
				(anchor circle)
			)
			(primitives
				(gr_poly
					(pts
						(arc
							(start -0.1778 -0.5715)
							(mid -0.321484 -0.511984)
							(end -0.381 -0.3683)
						)
						(arc
							(start -0.381 0.3683)
							(mid -0.321484 0.511984)
							(end -0.1778 0.5715)
						)
						(arc
							(start 0.1778 0.5715)
							(mid 0.321484 0.511984)
							(end 0.381 0.3683)
						)
						(arc
							(start 0.381 -0.3683)
							(mid 0.321484 -0.511984)
							(end 0.1778 -0.5715)
						)
					)
					(width 0)
					(fill yes)
				)
			)
		)
		(pad "S" smd custom
			(at -0.98425 0.9525 90)
			(size 0.1905 0.1905)
			(layers "B.Cu" "B.Mask" "B.Paste")
			(net "GND")
			(options
				(clearance outline)
				(anchor circle)
			)
			(primitives
				(gr_poly
					(pts
						(arc
							(start -0.1778 -0.5715)
							(mid -0.321484 -0.511984)
							(end -0.381 -0.3683)
						)
						(arc
							(start -0.381 0.3683)
							(mid -0.321484 0.511984)
							(end -0.1778 0.5715)
						)
						(arc
							(start 0.1778 0.5715)
							(mid 0.321484 0.511984)
							(end 0.381 0.3683)
						)
						(arc
							(start 0.381 -0.3683)
							(mid 0.321484 -0.511984)
							(end 0.1778 -0.5715)
						)
					)
					(width 0)
					(fill yes)
				)
			)
		)
	)
	(footprint ""
		(layer "B.Cu")
		(at 126.0094 -89.8144 180)
		(property "Reference" "R41"
			(at 0 0 0)
			(layer "B.SilkS")
			(hide yes)
			(effects
				(font
					(size 1.27 1.27)
				)
				(justify mirror)
			)
		)
		(property "Value" "4K7R2F-GP"
			(at -0.064008 -3.993896 180)
			(unlocked yes)
			(layer "B.Fab")
			(hide yes)
			(effects
				(font
					(size 1.016 1.016)
					(thickness 0.1524)
				)
				(justify mirror)
			)
		)
		(property "Device Type" "R402H16"
			(at -0.064008 -5.517896 180)
			(unlocked yes)
			(layer "B.Fab")
			(hide yes)
			(effects
				(font
					(size 1.016 1.016)
					(thickness 0.1524)
				)
				(justify mirror)
			)
		)
		(duplicate_pad_numbers_are_jumpers no)
		(fp_line
			(start 0.508 -0.9398)
			(end 0.508 0.9398)
			(stroke
				(width 0.1524)
				(type default)
			)
			(layer "B.SilkS")
		)
		(fp_line
			(start -0.508 -0.9398)
			(end 0.508 -0.9398)
			(stroke
				(width 0.1524)
				(type default)
			)
			(layer "B.SilkS")
		)
		(fp_rect
			(start 0.508 0.9398)
			(end -0.508 -0.9398)
			(stroke
				(width 0)
				(type default)
			)
			(fill no)
			(layer "B.CrtYd")
		)
		(fp_rect
			(start 0.508 0.9398)
			(end -0.508 -0.9398)
			(stroke
				(width 0)
				(type default)
			)
			(fill no)
			(layer "B.Fab")
		)
		(pad "1" smd custom
			(at 0 -0.4445)
			(size 0.1397 0.1397)
			(layers "B.Cu" "B.Mask" "B.Paste")
			(net "EXP_SIO_LOAD_OUT")
			(options
				(clearance outline)
				(anchor circle)
			)
			(primitives
				(gr_poly
					(pts
						(arc
							(start -0.1778 0.2794)
							(mid -0.249642 0.249642)
							(end -0.2794 0.1778)
						)
						(arc
							(start -0.2794 -0.1778)
							(mid -0.249642 -0.249642)
							(end -0.1778 -0.2794)
						)
						(arc
							(start 0.1778 -0.2794)
							(mid 0.249642 -0.249642)
							(end 0.2794 -0.1778)
						)
						(arc
							(start 0.2794 0.1778)
							(mid 0.249642 0.249642)
							(end 0.1778 0.2794)
						)
					)
					(width 0)
					(fill yes)
				)
			)
		)
		(pad "2" smd custom
			(at 0 0.4445)
			(size 0.1397 0.1397)
			(layers "B.Cu" "B.Mask" "B.Paste")
			(net "P1V8_E")
			(options
				(clearance outline)
				(anchor circle)
			)
			(primitives
				(gr_poly
					(pts
						(arc
							(start -0.1778 0.2794)
							(mid -0.249642 0.249642)
							(end -0.2794 0.1778)
						)
						(arc
							(start -0.2794 -0.1778)
							(mid -0.249642 -0.249642)
							(end -0.1778 -0.2794)
						)
						(arc
							(start 0.1778 -0.2794)
							(mid 0.249642 -0.249642)
							(end 0.2794 -0.1778)
						)
						(arc
							(start 0.2794 0.1778)
							(mid 0.249642 0.249642)
							(end 0.1778 0.2794)
						)
					)
					(width 0)
					(fill yes)
				)
			)
		)
	)
	(footprint ""
		(layer "B.Cu")
		(at 179.438808 -38.10889 90)
		(property "Reference" "C439"
			(at 0 0 90)
			(layer "B.SilkS")
			(hide yes)
			(effects
				(font
					(size 1.27 1.27)
				)
				(justify mirror)
			)
		)
		(property "Value" "SCD1U6D3V1KX-GP"
			(at 2.8321 -1.7399 90)
			(unlocked yes)
			(layer "B.Fab")
			(hide yes)
			(effects
				(font
					(size 1.016 1.016)
					(thickness 0.1524)
				)
				(justify mirror)
			)
		)
		(property "Device Type" "C0201H13"
			(at 2.8321 -3.2639 90)
			(unlocked yes)
			(layer "B.Fab")
			(hide yes)
			(effects
				(font
					(size 1.016 1.016)
					(thickness 0.1524)
				)
				(justify mirror)
			)
		)
		(duplicate_pad_numbers_are_jumpers no)
		(fp_rect
			(start 0.2794 0.6477)
			(end -0.2794 -0.6477)
			(stroke
				(width 0)
				(type default)
			)
			(fill no)
			(layer "B.CrtYd")
		)
		(fp_rect
			(start 0.2794 0.6477)
			(end -0.2794 -0.6477)
			(stroke
				(width 0)
				(type default)
			)
			(fill no)
			(layer "B.Fab")
		)
		(pad "1" smd custom
			(at 0 -0.2794 270)
			(size 0.0762 0.0762)
			(layers "B.Cu" "B.Mask" "B.Paste")
			(net "P0V975")
			(options
				(clearance outline)
				(anchor circle)
			)
			(primitives
				(gr_poly
					(pts
						(arc
							(start 0.1524 0.127)
							(mid 0.137521 0.162921)
							(end 0.1016 0.1778)
						)
						(arc
							(start -0.1016 0.1778)
							(mid -0.137521 0.162921)
							(end -0.1524 0.127)
						)
						(arc
							(start -0.1524 -0.127)
							(mid -0.137521 -0.162921)
							(end -0.1016 -0.1778)
						)
						(arc
							(start 0.1016 -0.1778)
							(mid 0.137521 -0.162921)
							(end 0.1524 -0.127)
						)
					)
					(width 0)
					(fill yes)
				)
			)
		)
		(pad "2" smd custom
			(at 0 0.2794 270)
			(size 0.0762 0.0762)
			(layers "B.Cu" "B.Mask" "B.Paste")
			(net "GND")
			(options
				(clearance outline)
				(anchor circle)
			)
			(primitives
				(gr_poly
					(pts
						(arc
							(start 0.1524 0.127)
							(mid 0.137521 0.162921)
							(end 0.1016 0.1778)
						)
						(arc
							(start -0.1016 0.1778)
							(mid -0.137521 0.162921)
							(end -0.1524 0.127)
						)
						(arc
							(start -0.1524 -0.127)
							(mid -0.137521 -0.162921)
							(end -0.1016 -0.1778)
						)
						(arc
							(start 0.1016 -0.1778)
							(mid 0.137521 -0.162921)
							(end 0.1524 -0.127)
						)
					)
					(width 0)
					(fill yes)
				)
			)
		)
	)
	(footprint ""
		(layer "B.Cu")
		(at 159.2326 -111.0996)
		(property "Reference" "C699"
			(at 0 0 0)
			(layer "B.SilkS")
			(hide yes)
			(effects
				(font
					(size 1.27 1.27)
				)
				(justify mirror)
			)
		)
		(property "Value" "SC10U16V5KX-7-GP-U"
			(at 0.0762 -6.1214 0)
			(unlocked yes)
			(layer "B.Fab")
			(hide yes)
			(effects
				(font
					(size 1.016 1.016)
					(thickness 0.1524)
				)
				(justify mirror)
			)
		)
		(property "Device Type" "C805H58"
			(at 0.0762 -8.1534 0)
			(unlocked yes)
			(layer "B.Fab")
			(hide yes)
			(effects
				(font
					(size 1.016 1.016)
					(thickness 0.1524)
				)
				(justify mirror)
			)
		)
		(duplicate_pad_numbers_are_jumpers no)
		(fp_line
			(start -0.635 0)
			(end 0.635 0)
			(stroke
				(width 0.508)
				(type default)
			)
			(layer "B.SilkS")
		)
		(fp_rect
			(start 0.9652 1.778)
			(end -0.9652 -1.778)
			(stroke
				(width 0)
				(type default)
			)
			(fill no)
			(layer "B.CrtYd")
		)
		(fp_poly
			(pts
				(xy 0.9652 -1.778) (xy -0.9652 -1.778) (xy -0.9652 1.778) (xy 0.9652 1.778)
			)
			(stroke
				(width 0)
				(type default)
			)
			(fill no)
			(layer "B.Fab")
		)
		(pad "1" smd rect
			(at 0 -0.9652 180)
			(size 1.397 1.143)
			(layers "B.Cu" "B.Mask" "B.Paste")
			(net "P12V_STBY_VIN_U11")
		)
		(pad "2" smd rect
			(at 0 0.9652 180)
			(size 1.397 1.143)
			(layers "B.Cu" "B.Mask" "B.Paste")
			(net "GND")
		)
	)
	(footprint ""
		(layer "B.Cu")
		(at 42.910252 -108.17098 -90)
		(property "Reference" "C347"
			(at 0 0 90)
			(layer "B.SilkS")
			(hide yes)
			(effects
				(font
					(size 1.27 1.27)
				)
				(justify mirror)
			)
		)
		(property "Value" "SC4D7U25V5KX-1-GP"
			(at 0.0762 -6.1214 270)
			(unlocked yes)
			(layer "B.Fab")
			(hide yes)
			(effects
				(font
					(size 1.016 1.016)
					(thickness 0.1524)
				)
				(justify mirror)
			)
		)
		(property "Device Type" "C805H58"
			(at 0.0762 -8.1534 270)
			(unlocked yes)
			(layer "B.Fab")
			(hide yes)
			(effects
				(font
					(size 1.016 1.016)
					(thickness 0.1524)
				)
				(justify mirror)
			)
		)
		(duplicate_pad_numbers_are_jumpers no)
		(fp_line
			(start -0.635 0)
			(end 0.635 0)
			(stroke
				(width 0.508)
				(type default)
			)
			(layer "B.SilkS")
		)
		(fp_rect
			(start 0.9652 1.778)
			(end -0.9652 -1.778)
			(stroke
				(width 0)
				(type default)
			)
			(fill no)
			(layer "B.CrtYd")
		)
		(fp_poly
			(pts
				(xy 0.9652 -1.778) (xy -0.9652 -1.778) (xy -0.9652 1.778) (xy 0.9652 1.778)
			)
			(stroke
				(width 0)
				(type default)
			)
			(fill no)
			(layer "B.Fab")
		)
		(pad "1" smd rect
			(at 0 -0.9652 90)
			(size 1.397 1.143)
			(layers "B.Cu" "B.Mask" "B.Paste")
			(net "P12V_STBY_SCC")
		)
		(pad "2" smd rect
			(at 0 0.9652 90)
			(size 1.397 1.143)
			(layers "B.Cu" "B.Mask" "B.Paste")
			(net "GND")
		)
	)
	(footprint ""
		(layer "B.Cu")
		(at 170.67149 -47.587154 -90)
		(property "Reference" "C406"
			(at 0 0 90)
			(layer "B.SilkS")
			(hide yes)
			(effects
				(font
					(size 1.27 1.27)
				)
				(justify mirror)
			)
		)
		(property "Value" "SC10U6D3V5KX-4GP"
			(at 0.0762 -6.1214 270)
			(unlocked yes)
			(layer "B.Fab")
			(hide yes)
			(effects
				(font
					(size 1.016 1.016)
					(thickness 0.1524)
				)
				(justify mirror)
			)
		)
		(property "Device Type" "C805H58"
			(at 0.0762 -8.1534 270)
			(unlocked yes)
			(layer "B.Fab")
			(hide yes)
			(effects
				(font
					(size 1.016 1.016)
					(thickness 0.1524)
				)
				(justify mirror)
			)
		)
		(duplicate_pad_numbers_are_jumpers no)
		(fp_line
			(start -0.635 0)
			(end 0.635 0)
			(stroke
				(width 0.508)
				(type default)
			)
			(layer "B.SilkS")
		)
		(fp_rect
			(start 0.9652 1.778)
			(end -0.9652 -1.778)
			(stroke
				(width 0)
				(type default)
			)
			(fill no)
			(layer "B.CrtYd")
		)
		(fp_poly
			(pts
				(xy 0.9652 -1.778) (xy -0.9652 -1.778) (xy -0.9652 1.778) (xy 0.9652 1.778)
			)
			(stroke
				(width 0)
				(type default)
			)
			(fill no)
			(layer "B.Fab")
		)
		(pad "1" smd rect
			(at 0 -0.9652 90)
			(size 1.397 1.143)
			(layers "B.Cu" "B.Mask" "B.Paste")
			(net "P0V975")
		)
		(pad "2" smd rect
			(at 0 0.9652 90)
			(size 1.397 1.143)
			(layers "B.Cu" "B.Mask" "B.Paste")
			(net "GND")
		)
	)
	(footprint ""
		(layer "B.Cu")
		(at 200.787 -35.3314 180)
		(property "Reference" "R208"
			(at 0 0 0)
			(layer "B.SilkS")
			(hide yes)
			(effects
				(font
					(size 1.27 1.27)
				)
				(justify mirror)
			)
		)
		(property "Value" "4K7R2F-GP"
			(at -0.064008 -3.993896 180)
			(unlocked yes)
			(layer "B.Fab")
			(hide yes)
			(effects
				(font
					(size 1.016 1.016)
					(thickness 0.1524)
				)
				(justify mirror)
			)
		)
		(property "Device Type" "R402H16"
			(at -0.064008 -5.517896 180)
			(unlocked yes)
			(layer "B.Fab")
			(hide yes)
			(effects
				(font
					(size 1.016 1.016)
					(thickness 0.1524)
				)
				(justify mirror)
			)
		)
		(duplicate_pad_numbers_are_jumpers no)
		(fp_line
			(start 0.508 -0.9398)
			(end 0.508 0.9398)
			(stroke
				(width 0.1524)
				(type default)
			)
			(layer "B.SilkS")
		)
		(fp_line
			(start -0.508 -0.9398)
			(end 0.508 -0.9398)
			(stroke
				(width 0.1524)
				(type default)
			)
			(layer "B.SilkS")
		)
		(fp_rect
			(start 0.508 0.9398)
			(end -0.508 -0.9398)
			(stroke
				(width 0)
				(type default)
			)
			(fill no)
			(layer "B.CrtYd")
		)
		(fp_rect
			(start 0.508 0.9398)
			(end -0.508 -0.9398)
			(stroke
				(width 0)
				(type default)
			)
			(fill no)
			(layer "B.Fab")
		)
		(pad "1" smd custom
			(at 0 -0.4445)
			(size 0.1397 0.1397)
			(layers "B.Cu" "B.Mask" "B.Paste")
			(net "P1V8_C")
			(options
				(clearance outline)
				(anchor circle)
			)
			(primitives
				(gr_poly
					(pts
						(arc
							(start -0.1778 0.2794)
							(mid -0.249642 0.249642)
							(end -0.2794 0.1778)
						)
						(arc
							(start -0.2794 -0.1778)
							(mid -0.249642 -0.249642)
							(end -0.1778 -0.2794)
						)
						(arc
							(start 0.1778 -0.2794)
							(mid 0.249642 -0.249642)
							(end 0.2794 -0.1778)
						)
						(arc
							(start 0.2794 0.1778)
							(mid 0.249642 0.249642)
							(end 0.1778 0.2794)
						)
					)
					(width 0)
					(fill yes)
				)
			)
		)
		(pad "2" smd custom
			(at 0 0.4445)
			(size 0.1397 0.1397)
			(layers "B.Cu" "B.Mask" "B.Paste")
			(net "IOC_EEPROM_A1")
			(options
				(clearance outline)
				(anchor circle)
			)
			(primitives
				(gr_poly
					(pts
						(arc
							(start -0.1778 0.2794)
							(mid -0.249642 0.249642)
							(end -0.2794 0.1778)
						)
						(arc
							(start -0.2794 -0.1778)
							(mid -0.249642 -0.249642)
							(end -0.1778 -0.2794)
						)
						(arc
							(start 0.1778 -0.2794)
							(mid 0.249642 -0.249642)
							(end 0.2794 -0.1778)
						)
						(arc
							(start 0.2794 0.1778)
							(mid 0.249642 0.249642)
							(end 0.1778 0.2794)
						)
					)
					(width 0)
					(fill yes)
				)
			)
		)
	)
)
